# T6G (Grand Teton) — schematic netlist excerpt (pin names and nets, part order shuffled) for the footprints in the layout excerpt that follows; sources: Cadence DE-HDL packaged netlist, KiCad conversion of 04192023_DAF0TMB3IC0_F0TG_MB_C_brd_V02_OCP.brd

R6260  Q_RES  0 5% CHIP  pkg 0402LF  page 179 : A = USB_HUB2_TI_VDD_MRP_USB3DN_TXDM1 ; B = P1V2_CPU0_USB2_DVDD12
R6321  Q_RES  47K 0.1% EMPTY  pkg 0402LF  page 178 : A = USB_HUB2_MRP_RESET_N ; B = GND

(kicad_pcb
	(version 20260206)
	(generator "pcbnew")
	(generator_version "10.0")
	(general
		(thickness 1.6)
		(legacy_teardrops no)
	)
	(paper "A4")
	(title_block
		(title "04192023_DAF0TMB3IC0_F0TG_MB_C_brd_V02_OCP.brd")
		(comment 1 "Grand Teton / footprints 2231-2232 of 8354")
	)
	(layers
		(0 "F.Cu" signal "TOP")
		(4 "In1.Cu" signal "GND")
		(6 "In2.Cu" signal "IN1")
		(8 "In3.Cu" signal "GND1")
		(10 "In4.Cu" signal "IN2")
		(12 "In5.Cu" signal "GND2")
		(14 "In6.Cu" signal "IN3")
		(16 "In7.Cu" signal "GND3")
		(18 "In8.Cu" signal "VCC")
		(20 "In9.Cu" signal "VCC1")
		(22 "In10.Cu" signal "GND4")
		(24 "In11.Cu" signal "IN4")
		(26 "In12.Cu" signal "GND5")
		(28 "In13.Cu" signal "IN5")
		(30 "In14.Cu" signal "GND6")
		(32 "In15.Cu" signal "IN6")
		(34 "In16.Cu" signal "GND7")
		(2 "B.Cu" signal "BOTTOM")
		(9 "F.Adhes" user "F.Adhesive")
		(11 "B.Adhes" user "B.Adhesive")
		(13 "F.Paste" user "Package Geometry/Pastemask Top")
		(15 "B.Paste" user "Package Geometry/Pastemask Bottom")
		(5 "F.SilkS" user "Ref Des/Silkscreen Top")
		(7 "B.SilkS" user "Ref Des/Silkscreen Bottom")
		(1 "F.Mask" user "Board Geometry/Soldermask Top")
		(3 "B.Mask" user "Board Geometry/Soldermask Bottom")
		(17 "Dwgs.User" user "User.Drawings")
		(19 "Cmts.User" user "User.Comments")
		(21 "Eco1.User" user "User.Eco1")
		(23 "Eco2.User" user "User.Eco2")
		(25 "Edge.Cuts" user "Board Geometry/Outline")
		(27 "Margin" user)
		(31 "F.CrtYd" user "Package Geometry/Place Bound Top")
		(29 "B.CrtYd" user "Package Geometry/Place Bound Bottom")
		(35 "F.Fab" user "Ref Des/Assembly Top")
		(33 "B.Fab" user "Ref Des/Assembly Bottom")
	)
	(footprint ""
		(layer "F.Cu")
		(at 101.421946 -54.882034 90)
		(property "Reference" "R6321"
			(at 0 0 90)
			(layer "F.SilkS")
			(hide yes)
			(effects
				(font
					(size 1.27 1.27)
				)
			)
		)
		(property "Value" ""
			(at 0 0 90)
			(layer "F.Fab")
			(effects
				(font
					(size 1.27 1.27)
				)
			)
		)
		(duplicate_pad_numbers_are_jumpers no)
		(fp_line
			(start 0.7874 -0.4064)
			(end 0.7874 0.4064)
			(stroke
				(width 0.1524)
				(type default)
			)
			(layer "F.SilkS")
		)
		(fp_line
			(start -0.7874 -0.4064)
			(end 0.7874 -0.4064)
			(stroke
				(width 0.1524)
				(type default)
			)
			(layer "F.SilkS")
		)
		(fp_line
			(start 0.7874 0.4064)
			(end -0.7874 0.4064)
			(stroke
				(width 0.1524)
				(type default)
			)
			(layer "F.SilkS")
		)
		(fp_line
			(start -0.7874 0.4064)
			(end -0.7874 -0.4064)
			(stroke
				(width 0.1524)
				(type default)
			)
			(layer "F.SilkS")
		)
		(fp_line
			(start -0.12065 -0.305054)
			(end -0.12065 -0.2794)
			(stroke
				(width 0.1)
				(type default)
			)
			(layer "F.Fab")
		)
		(fp_line
			(start -0.67945 -0.305054)
			(end -0.12065 -0.305054)
			(stroke
				(width 0.1)
				(type default)
			)
			(layer "F.Fab")
		)
		(fp_line
			(start 0.67945 -0.3048)
			(end 0.67945 0.3048)
			(stroke
				(width 0.1)
				(type default)
			)
			(layer "F.Fab")
		)
		(fp_line
			(start 0.12065 -0.3048)
			(end 0.67945 -0.3048)
			(stroke
				(width 0.1)
				(type default)
			)
			(layer "F.Fab")
		)
		(fp_line
			(start 0.12065 -0.2794)
			(end 0.12065 -0.3048)
			(stroke
				(width 0.1)
				(type default)
			)
			(layer "F.Fab")
		)
		(fp_line
			(start -0.12065 -0.2794)
			(end 0.12065 -0.2794)
			(stroke
				(width 0.1)
				(type default)
			)
			(layer "F.Fab")
		)
		(fp_line
			(start 0.120396 0.2794)
			(end -0.12065 0.2794)
			(stroke
				(width 0.1)
				(type default)
			)
			(layer "F.Fab")
		)
		(fp_line
			(start -0.12065 0.2794)
			(end -0.12065 0.3048)
			(stroke
				(width 0.1)
				(type default)
			)
			(layer "F.Fab")
		)
		(fp_line
			(start 0.67945 0.3048)
			(end 0.120396 0.3048)
			(stroke
				(width 0.1)
				(type default)
			)
			(layer "F.Fab")
		)
		(fp_line
			(start 0.120396 0.3048)
			(end 0.120396 0.2794)
			(stroke
				(width 0.1)
				(type default)
			)
			(layer "F.Fab")
		)
		(fp_line
			(start -0.12065 0.3048)
			(end -0.67945 0.3048)
			(stroke
				(width 0.1)
				(type default)
			)
			(layer "F.Fab")
		)
		(fp_line
			(start -0.67945 0.3048)
			(end -0.67945 -0.305054)
			(stroke
				(width 0.1)
				(type default)
			)
			(layer "F.Fab")
		)
		(pad "1" smd circle
			(at -0.40005 0 90)
			(size 0 0)
			(layers "F.Cu" "F.Mask" "F.Paste")
			(net "USB_HUB2_MRP_RESET_N")
		)
		(pad "2" smd circle
			(at 0.40005 0 90)
			(size 0 0)
			(layers "F.Cu" "F.Mask" "F.Paste")
			(net "GND")
		)
	)
	(footprint ""
		(layer "F.Cu")
		(at 111.422942 -19.9898 -90)
		(property "Reference" "R6260"
			(at 0 0 270)
			(layer "F.SilkS")
			(hide yes)
			(effects
				(font
					(size 1.27 1.27)
				)
			)
		)
		(property "Value" ""
			(at 0 0 270)
			(layer "F.Fab")
			(effects
				(font
					(size 1.27 1.27)
				)
			)
		)
		(duplicate_pad_numbers_are_jumpers no)
		(fp_line
			(start -0.7874 0.4064)
			(end -0.7874 -0.4064)
			(stroke
				(width 0.1524)
				(type default)
			)
			(layer "F.SilkS")
		)
		(fp_line
			(start 0.7874 0.4064)
			(end -0.7874 0.4064)
			(stroke
				(width 0.1524)
				(type default)
			)
			(layer "F.SilkS")
		)
		(fp_line
			(start -0.7874 -0.4064)
			(end 0.7874 -0.4064)
			(stroke
				(width 0.1524)
				(type default)
			)
			(layer "F.SilkS")
		)
		(fp_line
			(start 0.7874 -0.4064)
			(end 0.7874 0.4064)
			(stroke
				(width 0.1524)
				(type default)
			)
			(layer "F.SilkS")
		)
		(fp_line
			(start -0.67945 0.3048)
			(end -0.67945 -0.305054)
			(stroke
				(width 0.1)
				(type default)
			)
			(layer "F.Fab")
		)
		(fp_line
			(start -0.12065 0.3048)
			(end -0.67945 0.3048)
			(stroke
				(width 0.1)
				(type default)
			)
			(layer "F.Fab")
		)
		(fp_line
			(start 0.120396 0.3048)
			(end 0.120396 0.2794)
			(stroke
				(width 0.1)
				(type default)
			)
			(layer "F.Fab")
		)
		(fp_line
			(start 0.67945 0.3048)
			(end 0.120396 0.3048)
			(stroke
				(width 0.1)
				(type default)
			)
			(layer "F.Fab")
		)
		(fp_line
			(start -0.12065 0.2794)
			(end -0.12065 0.3048)
			(stroke
				(width 0.1)
				(type default)
			)
			(layer "F.Fab")
		)
		(fp_line
			(start 0.120396 0.2794)
			(end -0.12065 0.2794)
			(stroke
				(width 0.1)
				(type default)
			)
			(layer "F.Fab")
		)
		(fp_line
			(start -0.12065 -0.2794)
			(end 0.12065 -0.2794)
			(stroke
				(width 0.1)
				(type default)
			)
			(layer "F.Fab")
		)
		(fp_line
			(start 0.12065 -0.2794)
			(end 0.12065 -0.3048)
			(stroke
				(width 0.1)
				(type default)
			)
			(layer "F.Fab")
		)
		(fp_line
			(start 0.12065 -0.3048)
			(end 0.67945 -0.3048)
			(stroke
				(width 0.1)
				(type default)
			)
			(layer "F.Fab")
		)
		(fp_line
			(start 0.67945 -0.3048)
			(end 0.67945 0.3048)
			(stroke
				(width 0.1)
				(type default)
			)
			(layer "F.Fab")
		)
		(fp_line
			(start -0.67945 -0.305054)
			(end -0.12065 -0.305054)
			(stroke
				(width 0.1)
				(type default)
			)
			(layer "F.Fab")
		)
		(fp_line
			(start -0.12065 -0.305054)
			(end -0.12065 -0.2794)
			(stroke
				(width 0.1)
				(type default)
			)
			(layer "F.Fab")
		)
		(pad "1" smd circle
			(at -0.40005 0 270)
			(size 0 0)
			(layers "F.Cu" "F.Mask" "F.Paste")
			(net "USB_HUB2_TI_VDD_MRP_USB3DN_TXDM1")
		)
		(pad "2" smd circle
			(at 0.40005 0 270)
			(size 0 0)
			(layers "F.Cu" "F.Mask" "F.Paste")
			(net "P1V2_CPU0_USB2_DVDD12")
		)
	)
)
